#ISCELL
  mstr_symbols bom_note *
  *
#ISCELL
  mstr_symbols cad_note *
  *
#ISCELL
  mstr_symbols design_note *
  *
#ISCELL
  mstr_symbols intel_corp_bpage *
  *
#CELL
  mstr_discrete res *
  page136_i101
#CELL
  mstr_discrete res *
  page136_i102
#ISCELL
  mstr_symbols gnd *
  page136_i103
#ISCELL
  mstr_symbols p3v3_stby *
  page136_i124
#ISCELL
  mstr_standard offpage *
  page136_i125
#CELL
  mstr_discrete res *
  page136_i126
#ISCELL
  mstr_symbols p3v3_stby *
  page136_i127
#CELL
  dev_discrete cap_a *
  page136_i128
#ISCELL
  mstr_symbols gnd *
  page136_i129
#CELL
  mstr_ttl ttl1g126_a *
  page136_i130
#ISCELL
  mstr_symbols p3v3_stby *
  page136_i131
#ISCELL
  mstr_standard offpage *
  page136_i132
#CELL
  mstr_discrete res *
  page136_i133
#CELL
  mstr_discrete fet_n *
  page136_i134
#ISCELL
  mstr_symbols gnd *
  page136_i135
#ISCELL
  mstr_standard offpage *
  page136_i136
#CELL
  mstr_discrete res *
  page136_i139
#CELL
  mstr_discrete res *
  page136_i140
#ISCELL
  mstr_symbols gnd *
  page136_i141
#CELL
  mstr_discrete res *
  page136_i147
#CELL
  mstr_discrete res *
  page136_i148
#ISCELL
  mstr_symbols gnd *
  page136_i152
#ISCELL
  mstr_symbols p3v3_stby *
  page136_i154
#CELL
  mstr_discrete res *
  page136_i155
#CELL
  mstr_discrete res *
  page136_i156
#ISCELL
  mstr_symbols gnd *
  page136_i157
#ISCELL
  mstr_standard offpage *
  page136_i162
#ISCELL
  mstr_standard offpage *
  page136_i165
#ISCELL
  mstr_standard offpage *
  page136_i170
#CELL
  mstr_conn conn12_c73564003 *
  page136_i174
#ISCELL
  mstr_standard offpage *
  page136_i175
